# S9S_MB_2U (Grand Teton) — schematic netlist excerpt (pin names and nets, part order shuffled) for the footprints in the layout excerpt that follows; sources: Cadence DE-HDL packaged netlist, KiCad conversion of 03242023_DA0F0TMBIJ0_F0T_Motherboard_J_brd_V01_OCP.brd

PC184  Q_CAP  22UF 4V 20% X6S  pkg C0805  page 276 : A = PVCCFA_EHV_CPU0 ; B = GND
PC247_P0_7  Q_CAP  22UF 4V 20% X6S  pkg C0805  page 270 : A = PVCCIN_CPU0 ; B = GND
R1326  Q_RES  2K 1% EMPTY  pkg 0402LF  page 219 : A = PWRGD_DRAMPWRGD_CPU0_CD_R_LVC1 ; B = GND

(kicad_pcb
	(version 20260206)
	(generator "pcbnew")
	(generator_version "10.0")
	(general
		(thickness 1.6)
		(legacy_teardrops no)
	)
	(paper "A4")
	(title_block
		(title "03242023_DA0F0TMBIJ0_F0T_Motherboard_J_brd_V01_OCP.brd")
		(comment 1 "Grand Teton / footprints 4885-4887 of 6105")
	)
	(layers
		(0 "F.Cu" signal "TOP")
		(4 "In1.Cu" signal "GND")
		(6 "In2.Cu" signal "IN1")
		(8 "In3.Cu" signal "GND1")
		(10 "In4.Cu" signal "IN2")
		(12 "In5.Cu" signal "GND2")
		(14 "In6.Cu" signal "IN3")
		(16 "In7.Cu" signal "GND3")
		(18 "In8.Cu" signal "VCC")
		(20 "In9.Cu" signal "VCC1")
		(22 "In10.Cu" signal "GND4")
		(24 "In11.Cu" signal "IN4")
		(26 "In12.Cu" signal "GND5")
		(28 "In13.Cu" signal "IN5")
		(30 "In14.Cu" signal "GND6")
		(32 "In15.Cu" signal "IN6")
		(34 "In16.Cu" signal "GND7")
		(2 "B.Cu" signal "BOTTOM")
		(9 "F.Adhes" user "F.Adhesive")
		(11 "B.Adhes" user "B.Adhesive")
		(13 "F.Paste" user "Package Geometry/Pastemask Top")
		(15 "B.Paste" user "Package Geometry/Pastemask Bottom")
		(5 "F.SilkS" user "Ref Des/Silkscreen Top")
		(7 "B.SilkS" user "Ref Des/Silkscreen Bottom")
		(1 "F.Mask" user "Board Geometry/Soldermask Top")
		(3 "B.Mask" user "Board Geometry/Soldermask Bottom")
		(17 "Dwgs.User" user "User.Drawings")
		(19 "Cmts.User" user "User.Comments")
		(21 "Eco1.User" user "User.Eco1")
		(23 "Eco2.User" user "User.Eco2")
		(25 "Edge.Cuts" user "Board Geometry/Outline")
		(27 "Margin" user)
		(31 "F.CrtYd" user "Package Geometry/Place Bound Top")
		(29 "B.CrtYd" user "Package Geometry/Place Bound Bottom")
		(35 "F.Fab" user "Ref Des/Assembly Top")
		(33 "B.Fab" user "Ref Des/Assembly Bottom")
	)
	(footprint ""
		(layer "B.Cu")
		(at 174.814738 -97.32137 -90)
		(property "Reference" "R1326"
			(at 0 0 90)
			(layer "B.SilkS")
			(hide yes)
			(effects
				(font
					(size 1.27 1.27)
				)
				(justify mirror)
			)
		)
		(property "Value" ""
			(at 0 0 90)
			(layer "B.Fab")
			(effects
				(font
					(size 1.27 1.27)
				)
				(justify mirror)
			)
		)
		(duplicate_pad_numbers_are_jumpers no)
		(fp_line
			(start -0.7874 0.4064)
			(end 0.7874 0.4064)
			(stroke
				(width 0.1524)
				(type default)
			)
			(layer "B.SilkS")
		)
		(fp_line
			(start 0.7874 0.4064)
			(end 0.7874 -0.4064)
			(stroke
				(width 0.1524)
				(type default)
			)
			(layer "B.SilkS")
		)
		(fp_line
			(start -0.7874 -0.4064)
			(end -0.7874 0.4064)
			(stroke
				(width 0.1524)
				(type default)
			)
			(layer "B.SilkS")
		)
		(fp_line
			(start 0.7874 -0.4064)
			(end -0.7874 -0.4064)
			(stroke
				(width 0.1524)
				(type default)
			)
			(layer "B.SilkS")
		)
		(fp_line
			(start -0.67945 0.3048)
			(end -0.120396 0.3048)
			(stroke
				(width 0.1)
				(type default)
			)
			(layer "B.Fab")
		)
		(fp_line
			(start -0.120396 0.3048)
			(end -0.120396 0.2794)
			(stroke
				(width 0.1)
				(type default)
			)
			(layer "B.Fab")
		)
		(fp_line
			(start 0.12065 0.3048)
			(end 0.67945 0.3048)
			(stroke
				(width 0.1)
				(type default)
			)
			(layer "B.Fab")
		)
		(fp_line
			(start 0.67945 0.3048)
			(end 0.67945 -0.305054)
			(stroke
				(width 0.1)
				(type default)
			)
			(layer "B.Fab")
		)
		(fp_line
			(start -0.120396 0.2794)
			(end 0.12065 0.2794)
			(stroke
				(width 0.1)
				(type default)
			)
			(layer "B.Fab")
		)
		(fp_line
			(start 0.12065 0.2794)
			(end 0.12065 0.3048)
			(stroke
				(width 0.1)
				(type default)
			)
			(layer "B.Fab")
		)
		(fp_line
			(start -0.12065 -0.2794)
			(end -0.12065 -0.3048)
			(stroke
				(width 0.1)
				(type default)
			)
			(layer "B.Fab")
		)
		(fp_line
			(start 0.12065 -0.2794)
			(end -0.12065 -0.2794)
			(stroke
				(width 0.1)
				(type default)
			)
			(layer "B.Fab")
		)
		(fp_line
			(start -0.67945 -0.3048)
			(end -0.67945 0.3048)
			(stroke
				(width 0.1)
				(type default)
			)
			(layer "B.Fab")
		)
		(fp_line
			(start -0.12065 -0.3048)
			(end -0.67945 -0.3048)
			(stroke
				(width 0.1)
				(type default)
			)
			(layer "B.Fab")
		)
		(fp_line
			(start 0.12065 -0.305054)
			(end 0.12065 -0.2794)
			(stroke
				(width 0.1)
				(type default)
			)
			(layer "B.Fab")
		)
		(fp_line
			(start 0.67945 -0.305054)
			(end 0.12065 -0.305054)
			(stroke
				(width 0.1)
				(type default)
			)
			(layer "B.Fab")
		)
		(pad "1" smd circle
			(at 0.40005 0 90)
			(size 0 0)
			(layers "B.Cu" "B.Mask" "B.Paste")
			(net "PWRGD_DRAMPWRGD_CPU0_CD_R_LVC1")
		)
		(pad "2" smd circle
			(at -0.40005 0 90)
			(size 0 0)
			(layers "B.Cu" "B.Mask" "B.Paste")
			(net "GND")
		)
	)
	(footprint ""
		(layer "B.Cu")
		(at 327.522586 -333.628492 -90)
		(property "Reference" "PC247_P0_7"
			(at 0 0 90)
			(layer "B.SilkS")
			(hide yes)
			(effects
				(font
					(size 1.27 1.27)
				)
				(justify mirror)
			)
		)
		(property "Value" ""
			(at 0 0 90)
			(layer "B.Fab")
			(effects
				(font
					(size 1.27 1.27)
				)
				(justify mirror)
			)
		)
		(duplicate_pad_numbers_are_jumpers no)
		(fp_line
			(start -1.524 0.762)
			(end 1.524 0.762)
			(stroke
				(width 0.1524)
				(type default)
			)
			(layer "B.SilkS")
		)
		(fp_line
			(start 1.524 0.762)
			(end 1.524 -0.762)
			(stroke
				(width 0.1524)
				(type default)
			)
			(layer "B.SilkS")
		)
		(fp_line
			(start -1.524 -0.762)
			(end -1.524 0.762)
			(stroke
				(width 0.1524)
				(type default)
			)
			(layer "B.SilkS")
		)
		(fp_line
			(start 1.524 -0.762)
			(end -1.524 -0.762)
			(stroke
				(width 0.1524)
				(type default)
			)
			(layer "B.SilkS")
		)
		(fp_line
			(start -1.1049 0.724916)
			(end -1.1049 -0.724916)
			(stroke
				(width 0.1)
				(type default)
			)
			(layer "B.Fab")
		)
		(fp_line
			(start 1.1049 0.724916)
			(end -1.1049 0.724916)
			(stroke
				(width 0.1)
				(type default)
			)
			(layer "B.Fab")
		)
		(fp_line
			(start -1.1049 -0.724916)
			(end 1.1049 -0.724916)
			(stroke
				(width 0.1)
				(type default)
			)
			(layer "B.Fab")
		)
		(fp_line
			(start 1.1049 -0.724916)
			(end 1.1049 0.724916)
			(stroke
				(width 0.1)
				(type default)
			)
			(layer "B.Fab")
		)
		(pad "1" smd rect
			(at 0.889 0 270)
			(size 1.016 1.27)
			(layers "B.Cu" "B.Mask" "B.Paste")
			(net "PVCCIN_CPU0")
		)
		(pad "2" smd rect
			(at -0.889 0 270)
			(size 1.016 1.27)
			(layers "B.Cu" "B.Mask" "B.Paste")
			(net "GND")
		)
	)
	(footprint ""
		(layer "B.Cu")
		(at 409.30957 -156.642054 180)
		(property "Reference" "PC184"
			(at 0 0 0)
			(layer "B.SilkS")
			(hide yes)
			(effects
				(font
					(size 1.27 1.27)
				)
				(justify mirror)
			)
		)
		(property "Value" ""
			(at 0 0 0)
			(layer "B.Fab")
			(effects
				(font
					(size 1.27 1.27)
				)
				(justify mirror)
			)
		)
		(duplicate_pad_numbers_are_jumpers no)
		(fp_line
			(start 1.524 0.762)
			(end 1.524 -0.762)
			(stroke
				(width 0.1524)
				(type default)
			)
			(layer "B.SilkS")
		)
		(fp_line
			(start 1.524 -0.762)
			(end -1.524 -0.762)
			(stroke
				(width 0.1524)
				(type default)
			)
			(layer "B.SilkS")
		)
		(fp_line
			(start -1.524 0.762)
			(end 1.524 0.762)
			(stroke
				(width 0.1524)
				(type default)
			)
			(layer "B.SilkS")
		)
		(fp_line
			(start -1.524 -0.762)
			(end -1.524 0.762)
			(stroke
				(width 0.1524)
				(type default)
			)
			(layer "B.SilkS")
		)
		(fp_line
			(start 1.1049 0.724916)
			(end -1.1049 0.724916)
			(stroke
				(width 0.1)
				(type default)
			)
			(layer "B.Fab")
		)
		(fp_line
			(start 1.1049 -0.724916)
			(end 1.1049 0.724916)
			(stroke
				(width 0.1)
				(type default)
			)
			(layer "B.Fab")
		)
		(fp_line
			(start -1.1049 0.724916)
			(end -1.1049 -0.724916)
			(stroke
				(width 0.1)
				(type default)
			)
			(layer "B.Fab")
		)
		(fp_line
			(start -1.1049 -0.724916)
			(end 1.1049 -0.724916)
			(stroke
				(width 0.1)
				(type default)
			)
			(layer "B.Fab")
		)
		(pad "1" smd rect
			(at 0.889 0 180)
			(size 1.016 1.27)
			(layers "B.Cu" "B.Mask" "B.Paste")
			(net "PVCCFA_EHV_CPU0")
		)
		(pad "2" smd rect
			(at -0.889 0 180)
			(size 1.016 1.27)
			(layers "B.Cu" "B.Mask" "B.Paste")
			(net "GND")
		)
	)
)
